# BASEBOARD_FAB2 (Tioga Pass) — schematic netlist excerpt (pin names and nets, part order shuffled) for the footprints in the layout excerpt that follows; sources: Cadence DE-HDL packaged netlist, KiCad conversion of Wiwynn_Tioga_Pass_MB.brd

Q1D2  FET_N  2N7002 FET  pkg SOT23LF  page 200
  GATE  = FM_OC_DETECT_EN_N
  SRC  = GND
  DRN  = FM_OC_DETECT_EN

C7B28  CAP  0.22UF 16V 10% X7R  pkg 0402  page 129 : A = DMI_CPU0_PCH_TX_DP<1> ; B = DMI_CPU0_PCH_TX_C_DP<1>
C7A7  CAP  1.0UF 16V 10% X6S  pkg 0402  page 236 : A = VR_FET_SW_P12V_STBY_PVDDQ_DEF ; B = GND

(kicad_pcb
	(version 20260206)
	(generator "pcbnew")
	(generator_version "10.0")
	(general
		(thickness 1.6)
		(legacy_teardrops no)
	)
	(paper "A4")
	(title_block
		(title "Wiwynn_Tioga_Pass_MB.brd")
		(comment 1 "Tioga Pass / footprints 147-149 of 4770")
	)
	(layers
		(0 "F.Cu" signal "TOP")
		(4 "In1.Cu" signal "L2GND")
		(6 "In2.Cu" signal "L3")
		(8 "In3.Cu" signal "L4GND")
		(10 "In4.Cu" signal "L5")
		(12 "In5.Cu" signal "L6GND")
		(14 "In6.Cu" signal "L7VCC")
		(16 "In7.Cu" signal "L8VCC")
		(18 "In8.Cu" signal "L9GND")
		(20 "In9.Cu" signal "L10")
		(22 "In10.Cu" signal "L11GND")
		(24 "In11.Cu" signal "L12")
		(26 "In12.Cu" signal "L13GND")
		(2 "B.Cu" signal "BOTTOM")
		(9 "F.Adhes" user "F.Adhesive")
		(11 "B.Adhes" user "B.Adhesive")
		(13 "F.Paste" user "Package Geometry/Pastemask Top")
		(15 "B.Paste" user "Package Geometry/Pastemask Bottom")
		(5 "F.SilkS" user "Ref Des/Silkscreen Top")
		(7 "B.SilkS" user "Ref Des/Silkscreen Bottom")
		(1 "F.Mask" user "Board Geometry/Soldermask Top")
		(3 "B.Mask" user "Board Geometry/Soldermask Bottom")
		(17 "Dwgs.User" user "User.Drawings")
		(19 "Cmts.User" user "User.Comments")
		(21 "Eco1.User" user "User.Eco1")
		(23 "Eco2.User" user "User.Eco2")
		(25 "Edge.Cuts" user "Board Geometry/Outline")
		(27 "Margin" user)
		(31 "F.CrtYd" user "Package Geometry/Place Bound Top")
		(29 "B.CrtYd" user "Package Geometry/Place Bound Bottom")
		(35 "F.Fab" user "Ref Des/Assembly Top")
		(33 "B.Fab" user "Ref Des/Assembly Bottom")
	)
	(footprint ""
		(layer "F.Cu")
		(at 364.617 -112.395 90)
		(property "Reference" "C7B28"
			(at 0 0 90)
			(layer "F.SilkS")
			(hide yes)
			(effects
				(font
					(size 1.27 1.27)
				)
			)
		)
		(property "Value" ""
			(at 0 0 90)
			(layer "F.Fab")
			(effects
				(font
					(size 1.27 1.27)
				)
			)
		)
		(duplicate_pad_numbers_are_jumpers no)
		(fp_poly
			(pts
				(xy 0.3048 -0.1016) (xy 0.3048 0.9906) (xy -0.3048 0.9906) (xy -0.3048 -0.1016)
			)
			(stroke
				(width 0)
				(type default)
			)
			(fill no)
			(layer "F.CrtYd")
		)
		(fp_line
			(start 0.3048 -0.1016)
			(end -0.3048 -0.1016)
			(stroke
				(width 0.1)
				(type default)
			)
			(layer "F.Fab")
		)
		(fp_line
			(start -0.3048 -0.1016)
			(end -0.3048 0.9906)
			(stroke
				(width 0.1)
				(type default)
			)
			(layer "F.Fab")
		)
		(fp_line
			(start 0.3048 0.9906)
			(end 0.3048 -0.1016)
			(stroke
				(width 0.1)
				(type default)
			)
			(layer "F.Fab")
		)
		(fp_line
			(start -0.3048 0.9906)
			(end 0.3048 0.9906)
			(stroke
				(width 0.1)
				(type default)
			)
			(layer "F.Fab")
		)
		(pad "1" smd rect
			(at 0 0 90)
			(size 0.508 0.508)
			(layers "F.Cu" "F.Mask" "F.Paste")
			(net "DMI_CPU0_PCH_TX_DP<1>")
		)
		(pad "2" smd rect
			(at 0 0.889 90)
			(size 0.508 0.508)
			(layers "F.Cu" "F.Mask" "F.Paste")
			(net "DMI_CPU0_PCH_TX_C_DP<1>")
		)
		(zone
			(layer "F.Cu")
			(hatch none 0.5)
			(connect_pads
				(clearance 0)
			)
			(min_thickness 0.25)
			(keepout
				(tracks allowed)
				(vias not_allowed)
				(pads allowed)
				(copperpour not_allowed)
				(footprints allowed)
			)
			(placement
				(enabled no)
				(sheetname "")
			)
			(fill
				(thermal_gap 0.5)
				(thermal_bridge_width 0.5)
				(island_removal_mode 0)
			)
			(polygon
				(pts
					(xy 364.871 -112.141) (xy 364.871 -112.649) (xy 365.252 -112.649) (xy 365.252 -112.141)
				)
			)
		)
		(zone
			(layer "F.Cu")
			(hatch none 0.5)
			(connect_pads
				(clearance 0)
			)
			(min_thickness 0.25)
			(keepout
				(tracks not_allowed)
				(vias allowed)
				(pads allowed)
				(copperpour not_allowed)
				(footprints allowed)
			)
			(placement
				(enabled no)
				(sheetname "")
			)
			(fill
				(thermal_gap 0.5)
				(thermal_bridge_width 0.5)
				(island_removal_mode 0)
			)
			(polygon
				(pts
					(xy 365.252 -112.141) (xy 365.252 -112.649) (xy 364.871 -112.649) (xy 364.871 -112.141)
				)
			)
		)
	)
	(footprint ""
		(layer "F.Cu")
		(at 25.0698 -77.1906 90)
		(property "Reference" "Q1D2"
			(at -4.1402 1.60147 90)
			(unlocked yes)
			(layer "F.SilkS")
			(effects
				(font
					(size 0.7874 0.5842)
					(thickness 0.1524)
				)
				(justify left)
			)
		)
		(property "Value" ""
			(at 0 0 90)
			(layer "F.Fab")
			(effects
				(font
					(size 1.27 1.27)
				)
			)
		)
		(duplicate_pad_numbers_are_jumpers no)
		(fp_line
			(start 1.778 -0.5715)
			(end 1.778 0.3175)
			(stroke
				(width 0.1524)
				(type default)
			)
			(layer "F.SilkS")
		)
		(fp_line
			(start 0.9525 -0.5715)
			(end 1.778 -0.5715)
			(stroke
				(width 0.1524)
				(type default)
			)
			(layer "F.SilkS")
		)
		(fp_line
			(start 0.381 0.635)
			(end 0.381 1.27)
			(stroke
				(width 0.1524)
				(type default)
			)
			(layer "F.SilkS")
		)
		(fp_line
			(start 1.778 2.4765)
			(end 1.778 1.5875)
			(stroke
				(width 0.1524)
				(type default)
			)
			(layer "F.SilkS")
		)
		(fp_line
			(start 0.9525 2.4765)
			(end 1.778 2.4765)
			(stroke
				(width 0.1524)
				(type default)
			)
			(layer "F.SilkS")
		)
		(fp_circle
			(center -0.9525 -0.9271)
			(end -0.9525 -0.8001)
			(stroke
				(width 0.254)
				(type default)
			)
			(fill no)
			(layer "F.SilkS")
		)
		(fp_poly
			(pts
				(xy 1.778 2.4765) (xy 0.381 2.4765) (xy 0.381 -0.5715) (xy 1.778 -0.5715)
			)
			(stroke
				(width 0)
				(type default)
			)
			(fill no)
			(layer "F.CrtYd")
		)
		(fp_line
			(start 1.778 -0.5715)
			(end 0.381 -0.5715)
			(stroke
				(width 0.1)
				(type default)
			)
			(layer "F.Fab")
		)
		(fp_line
			(start 0.381 -0.5715)
			(end 0.381 2.4765)
			(stroke
				(width 0.1)
				(type default)
			)
			(layer "F.Fab")
		)
		(fp_line
			(start 1.778 2.4765)
			(end 1.778 -0.5715)
			(stroke
				(width 0.1)
				(type default)
			)
			(layer "F.Fab")
		)
		(fp_line
			(start 0.381 2.4765)
			(end 1.778 2.4765)
			(stroke
				(width 0.1)
				(type default)
			)
			(layer "F.Fab")
		)
		(fp_circle
			(center -0.9525 -0.9271)
			(end -0.9525 -0.8001)
			(stroke
				(width 0.254)
				(type default)
			)
			(fill no)
			(layer "F.Fab")
		)
		(pad "1" smd rect
			(at 0 0 90)
			(size 1.143 0.508)
			(layers "F.Cu" "F.Mask" "F.Paste")
			(net "FM_OC_DETECT_EN_N")
		)
		(pad "2" smd rect
			(at 0 1.905 90)
			(size 1.143 0.508)
			(layers "F.Cu" "F.Mask" "F.Paste")
			(net "GND")
		)
		(pad "3" smd rect
			(at 2.159 0.9525 90)
			(size 1.143 0.508)
			(layers "F.Cu" "F.Mask" "F.Paste")
			(net "FM_OC_DETECT_EN")
		)
	)
	(footprint ""
		(layer "F.Cu")
		(at 379.725428 -154.266646)
		(property "Reference" "C7A7"
			(at 0 0 0)
			(layer "F.SilkS")
			(hide yes)
			(effects
				(font
					(size 1.27 1.27)
				)
			)
		)
		(property "Value" ""
			(at 0 0 0)
			(layer "F.Fab")
			(effects
				(font
					(size 1.27 1.27)
				)
			)
		)
		(duplicate_pad_numbers_are_jumpers no)
		(fp_poly
			(pts
				(xy 0.3048 -0.1016) (xy 0.3048 0.9906) (xy -0.3048 0.9906) (xy -0.3048 -0.1016)
			)
			(stroke
				(width 0)
				(type default)
			)
			(fill no)
			(layer "F.CrtYd")
		)
		(fp_line
			(start -0.3048 -0.1016)
			(end -0.3048 0.9906)
			(stroke
				(width 0.1)
				(type default)
			)
			(layer "F.Fab")
		)
		(fp_line
			(start -0.3048 0.9906)
			(end 0.3048 0.9906)
			(stroke
				(width 0.1)
				(type default)
			)
			(layer "F.Fab")
		)
		(fp_line
			(start 0.3048 -0.1016)
			(end -0.3048 -0.1016)
			(stroke
				(width 0.1)
				(type default)
			)
			(layer "F.Fab")
		)
		(fp_line
			(start 0.3048 0.9906)
			(end 0.3048 -0.1016)
			(stroke
				(width 0.1)
				(type default)
			)
			(layer "F.Fab")
		)
		(pad "1" smd rect
			(at 0 0)
			(size 0.508 0.508)
			(layers "F.Cu" "F.Mask" "F.Paste")
			(net "VR_FET_SW_P12V_STBY_PVDDQ_DEF")
		)
		(pad "2" smd rect
			(at 0 0.889)
			(size 0.508 0.508)
			(layers "F.Cu" "F.Mask" "F.Paste")
			(net "GND")
		)
		(zone
			(layer "F.Cu")
			(hatch none 0.5)
			(connect_pads
				(clearance 0)
			)
			(min_thickness 0.25)
			(keepout
				(tracks allowed)
				(vias not_allowed)
				(pads allowed)
				(copperpour not_allowed)
				(footprints allowed)
			)
			(placement
				(enabled no)
				(sheetname "")
			)
			(fill
				(thermal_gap 0.5)
				(thermal_bridge_width 0.5)
				(island_removal_mode 0)
			)
			(polygon
				(pts
					(xy 379.471428 -154.012646) (xy 379.979428 -154.012646) (xy 379.979428 -153.631646) (xy 379.471428 -153.631646)
				)
			)
		)
		(zone
			(layer "F.Cu")
			(hatch none 0.5)
			(connect_pads
				(clearance 0)
			)
			(min_thickness 0.25)
			(keepout
				(tracks not_allowed)
				(vias allowed)
				(pads allowed)
				(copperpour not_allowed)
				(footprints allowed)
			)
			(placement
				(enabled no)
				(sheetname "")
			)
			(fill
				(thermal_gap 0.5)
				(thermal_bridge_width 0.5)
				(island_removal_mode 0)
			)
			(polygon
				(pts
					(xy 379.471428 -153.631646) (xy 379.979428 -153.631646) (xy 379.979428 -154.012646) (xy 379.471428 -154.012646)
				)
			)
		)
	)
)
